FILE_TYPE = CONNECTIVITY;
{Allegro Design Entry HDL 17.4-2019 S026 (4007227) 1/17/2022}
"PAGE_NUMBER" = 263;
0"NC";
1"GND\g";
2"GND\g";
3"P5V_AUX\g";
4"GND\g";
5"GND\g";
6"GND\g";
7"GND\g";
8"P3V3_AUX\g";
9"P1V2_AUX\g";
10"GND\g";
11"GND\g";
12"GND\g";
13"GND\g";
14"P1V8_CPU0_RT_1D\g";
15"GND\g";
16"GND\g";
17"GND\g";
18"P1V8_CPU1_RT_1D\g";
19"GND\g";
20"P1V8_AUX\g";
21"GND\g";
22"GND\g";
23"PVDD_33_S5\g";
24"GND\g";
25"GND\g";
26"GND\g";
27"PVDD18_S5_P0\g";
28"GND\g";
29"GND\g";
30"GND\g";
31"PVDD18_S5_P1\g";
32"GND\g";
33"GND\g";
34"GND\g";
35"GND\g";
36"GND\g";
37"GND\g";
38"GND\g";
39"GND\g";
40"GND\g";
41"P3V3_AUX\g";
42"GND\g";
43"MAX11617_2_VREF_R";
44"GND\g";
45"GND\g";
46"P3V3_MAX11617_2_VDD";
47"P1V8_CPU1_RT_1D_ADC_MAM"CDS_PHYS_NET_NAME"P3V3_AUX_ADC_MAM";
48"P1V2_AUX_ADC_MAM"CDS_PHYS_NET_NAME"P12V_OCP_V3_2_ISENSE_MAM";
49"SMB_SEN_MAM_2_3V3AUX_SDA"CDS_PHYS_NET_NAME"SMB_SEN_MAM_3V3AUX_SDA";
50"P1V2_AUX_ADC_MAM"CDS_PHYS_NET_NAME"P3V3_AUX_ADC_MAM";
51"P1V2_AUX_ADC_TIC"CDS_PHYS_NET_NAME"P3V3_AUX_ADC_TIC";
52"P1V8_CPU0_RT_1D_ADC_MAM"CDS_PHYS_NET_NAME"P3V3_AUX_ADC_MAM";
53"P1V8_CPU0_RT_1D_ADC_TIC"CDS_PHYS_NET_NAME"P3V3_AUX_ADC_TIC";
54"SMB_SEN_MAM_2_3V3AUX_SDA"CDS_PHYS_NET_NAME"SMB_SEN_MAM_3V3AUX_SDA";
55"SMB_SEN_MAM_2_3V3AUX_SCL"CDS_PHYS_NET_NAME"SMB_SEN_MAM_3V3AUX_SCL";
56"SMB_ADC_SCL_R"CDS_PHYS_NET_NAME"SMB_SCM_2_R4_SCL";
57"P1V8_CPU1_RT_1D_ADC_MAM"CDS_PHYS_NET_NAME"P3V3_ADC_MAM";
58"SMB_ADC_SDA_R"CDS_PHYS_NET_NAME"SMB_SCM_2_R4_SDA";
59"SMB_SEN_MAM_2_3V3AUX_SCL"CDS_PHYS_NET_NAME"SMB_SEN_MAM_3V3AUX_SCL";
60"PVDD18_S5_P1_ADC_MAM"CDS_PHYS_NET_NAME"P3V3_AUX_ADC_MAM";
61"GND\g";
62"P3V3_AUX\g";
63"PVDD18_S5_P1_ADC_TIC"CDS_PHYS_NET_NAME"P3V3_AUX_ADC_TIC";
64"PVDD18_S5_P1_ADC"CDS_PHYS_NET_NAME"P3V3_AUX_ADC";
65"PVDD18_S5_P0_ADC_TIC"CDS_PHYS_NET_NAME"P3V3_AUX_ADC_TIC";
66"PVDD18_S5_P0_ADC_MAM"CDS_PHYS_NET_NAME"P3V3_AUX_ADC_MAM";
67"PVDD18_S5_P0_ADC"CDS_PHYS_NET_NAME"P3V3_AUX_ADC";
68"PVDD_33_S5_ADC_MAM"CDS_PHYS_NET_NAME"P3V3_AUX_ADC_MAM";
69"P1V8_CPU1_RT_1D_ADC_TIC"CDS_PHYS_NET_NAME"P3V3_AUX_ADC_TIC";
70"P1V8_CPU1_RT_1D_ADC"CDS_PHYS_NET_NAME"P3V3_AUX_ADC";
71"P1V8_AUX_ADC_TIC"CDS_PHYS_NET_NAME"P3V3_ADC_TIC";
72"PVDD_33_S5_ADC"CDS_PHYS_NET_NAME"P3V3_AUX_ADC";
73"P1V8_CPU0_RT_1D_ADC"CDS_PHYS_NET_NAME"P3V3_AUX_ADC";
74"P1V2_AUX_ADC"CDS_PHYS_NET_NAME"P3V3_AUX_ADC";
75"P1V8_AUX_ADC_MAM"CDS_PHYS_NET_NAME"P3V3_ADC_MAM";
76"P5V_AUX_ADC_MAM"CDS_PHYS_NET_NAME"P5V_ADC_MAM";
77"P5V_AUX_ADC_TIC"CDS_PHYS_NET_NAME"P5V_ADC_TIC";
78"P5V_AUX_ADC"CDS_PHYS_NET_NAME"P5V_ADC";
79"MAX11617_2_VREF";
80"P1V8_CPU0_RT_1D_ADC_MAM"CDS_PHYS_NET_NAME"P5V_ADC_MAM";
81"PVDD_33_S5_ADC_TIC"CDS_PHYS_NET_NAME"P3V3_AUX_ADC_TIC";
82"P1V8_AUX_ADC"CDS_PHYS_NET_NAME"P3V3_ADC";
83"P3V3_ADC128_2_VCC";
84"ADC128_2_VREF"CDS_PHYS_NET_NAME"ADC128_VREF";
85"ADC128_2_A0"CDS_PHYS_NET_NAME"ADC128_A0";
86"PVDD18_S5_P1_ADC_TIC"CDS_PHYS_NET_NAME"P12V_E1S_0_ISENSE_TIC";
87"PVDD18_S5_P0_ADC_TIC"CDS_PHYS_NET_NAME"P3V3_PDB_AUX_ADC_TIC";
88"PVDD_33_S5_ADC_TIC"CDS_PHYS_NET_NAME"P3V3_AUX_ADC_TIC";
89"P1V8_CPU1_RT_1D_ADC_TIC"CDS_PHYS_NET_NAME"P3V3_ADC_TIC";
90"P1V8_CPU0_RT_1D_ADC_TIC"CDS_PHYS_NET_NAME"P5V_ADC_TIC";
91"P1V2_AUX_ADC_TIC"CDS_PHYS_NET_NAME"P12V_OCP_V3_2_ISENSE_TIC";
92"P1V8_AUX_ADC_TIC"CDS_PHYS_NET_NAME"P12V_OCP_SFF_ISENSE_TIC";
93"P5V_AUX_ADC_TIC"CDS_PHYS_NET_NAME"P12V_AUX_ADC_TIC";
94"ADC128_2_A1"CDS_PHYS_NET_NAME"ADC128_A1";
95"ADC128_2_A0"CDS_PHYS_NET_NAME"ADC128_A0";
96"SMB_ADC_SCL_R"CDS_PHYS_NET_NAME"SMB_SCM_2_R4_SCL";
97"SMB_ADC_SDA_R"CDS_PHYS_NET_NAME"SMB_SCM_2_R4_SDA";
98"SMB_SEN_TIC_2_3V3AUX_SDA"CDS_PHYS_NET_NAME"SMB_SEN_TIC_3V3AUX_SDA";
99"SMB_SEN_TIC_2_3V3AUX_SDA"CDS_PHYS_NET_NAME"SMB_SEN_TIC_3V3AUX_SDA";
100"SMB_SEN_TIC_2_3V3AUX_SCL"CDS_PHYS_NET_NAME"SMB_SEN_TIC_3V3AUX_SCL";
101"ADC128_2_A1"CDS_PHYS_NET_NAME"ADC128_A1";
102"TP_ADC128_2_INT"CDS_PHYS_NET_NAME"TP_ADC128_INT";
103"PVDD_33_S5_ADC_MAM"CDS_PHYS_NET_NAME"P3V3_AUX_ADC_MAM";
104"SMB_SEN_TIC_2_3V3AUX_SCL"CDS_PHYS_NET_NAME"SMB_SEN_TIC_3V3AUX_SCL";
105"P5V_AUX_ADC_MAM"CDS_PHYS_NET_NAME"P12V_AUX_ADC_MAM";
106"P1V8_AUX_ADC_MAM"CDS_PHYS_NET_NAME"P12V_OCP_SFF_ISENSE_MAM";
107"PVDD18_S5_P1_ADC_MAM"CDS_PHYS_NET_NAME"P12V_E1S_0_ISENSE_MAM";
108"PVDD18_S5_P0_ADC_MAM"CDS_PHYS_NET_NAME"P3V3_PDB_AUX_ADC_MAM";
%"UNIVERSAL_GND"
"1","(-4150,5000)","0","pure_quanta_power","I114";
;
CDS_LIB"pure_quanta_power"
HDL_POWER"GND";
"A"1;
%"Q_CAP"
"1","(-4150,5200)","2","pure_quanta","I115";
;
LOCATION"C1074"
$SEC"1"
CDS_SEC"1"
PACK_TYPE"0402"
MATERIAL"X7R"
TOLERANCE"10%"
VOLTAGE"25V"
VALUE"0.1UF"
CDS_LIB"pure_quanta"
PART_NUMBER"CH4104K1B00";
"B"
$PN"2"1;
"A"
$PN"1"79;
%"UNIVERSAL_GND"
"1","(-3425,1525)","0","pure_quanta_power","I118";
;
CDS_LIB"pure_quanta_power"
HDL_POWER"GND";
"A"2;
%"Q_RES"
"2","(-3425,1850)","0","pure_quanta","I119";
;
LOCATION"R1268"
$SEC"1"
CDS_SEC"1"
VALUE"4.7K"
MATERIAL"EMPTY"
WATTAGE"1/16W"
TOLERANCE"1%"
ROOM"ADC_TI_BOM1"
PACK_TYPE"0402LF"
CDS_LIB"pure_quanta"
PART_NUMBER"CS24702FB06";
"A"
$PN"1"84;
"B"
$PN"2"2;
%"Q_RES"
"2","(-9025,5475)","0","pure_quanta","I12";
;
LOCATION"R1226"
$SEC"1"
CDS_SEC"1"
TOLERANCE"1%"
MATERIAL"CHIP"
WATTAGE"1/16W"
VALUE"9.09K"
PACK_TYPE"0402LF"
CDS_LIB"pure_quanta"
PART_NUMBER"CS29092FB05";
"A"
$PN"1"78;
"B"
$PN"2"42;
%"Q_RES"
"2","(-9025,6025)","0","pure_quanta","I13";
;
LOCATION"R1238"
$SEC"1"
CDS_SEC"1"
WATTAGE"1/16W"
MATERIAL"CHIP"
PACK_TYPE"0402LF"
TOLERANCE"1%"
VALUE"18K"
CDS_LIB"pure_quanta"
PART_NUMBER"CS31802FB04";
"A"
$PN"1"3;
"B"
$PN"2"78;
%"Q_CAP"
"1","(-3800,2350)","0","pure_quanta","I130";
;
LOCATION"C1095"
$SEC"1"
CDS_SEC"1"
TOLERANCE"10%"
PACK_TYPE"0402"
MATERIAL"X7R"
VALUE"0.1UF"
VOLTAGE"25V"
ROOM"ADC_TI_BOM1"
CDS_LIB"pure_quanta"
PART_NUMBER"CH4104K1B00";
"B"
$PN"2"61;
"A"
$PN"1"83;
%"Q_RES"
"2","(-3425,2350)","0","pure_quanta","I131";
;
LOCATION"R1267"
$SEC"1"
CDS_SEC"1"
ROOM"ADC_TI_BOM1"
VALUE"4.7K"
TOLERANCE"1%"
MATERIAL"EMPTY"
WATTAGE"1/16W"
PACK_TYPE"0402LF"
CDS_LIB"pure_quanta"
PART_NUMBER"CS24702FB06";
"A"
$PN"1"83;
"B"
$PN"2"84;
%"Q_RES"
"1","(-2350,3550)","0","pure_quanta","I138";
;
LOCATION"R1227"
$SEC"1"
CDS_SEC"1"
VALUE"0"
TOLERANCE"5%"
ROOM"ADC_MAM_BOM2"
PACK_TYPE"0402LF"
WATTAGE"1/16W"
MATERIAL"EMPTY"
CDS_LIB"pure_quanta"
PART_NUMBER"CS00002JB13";
"B"
$PN"2"54;
"A"
$PN"1"58;
%"Q_RES"
"1","(-2350,3500)","0","pure_quanta","I139";
;
LOCATION"R1228"
$SEC"1"
CDS_SEC"1"
MATERIAL"EMPTY"
TOLERANCE"5%"
VALUE"0"
ROOM"ADC_MAM_BOM2"
WATTAGE"1/16W"
PACK_TYPE"0402LF"
CDS_LIB"pure_quanta"
PART_NUMBER"CS00002JB13";
"B"
$PN"2"55;
"A"
$PN"1"56;
%"UNIVERSAL_POWER"
"1","(-9025,6275)","0","pure_quanta_power","I14";
;
HDL_POWER"P5V_AUX"
CDS_LIB"pure_quanta_power";
"A"3;
%"Q_RES"
"1","(-1500,850)","0","pure_quanta","I140";
;
LOCATION"R1244"
$SEC"1"
CDS_SEC"1"
ROOM"ADC_TI_BOM1"
MATERIAL"CHIP"
TOLERANCE"5%"
VALUE"0"
WATTAGE"1/16W"
CDS_LIB"pure_quanta"
PACK_TYPE"0402LF"
PART_NUMBER"CS00002JB13";
"B"
$PN"2"100;
"A"
$PN"1"96;
%"Q_RES"
"1","(-1500,900)","0","pure_quanta","I141";
;
LOCATION"R1243"
$SEC"1"
CDS_SEC"1"
PACK_TYPE"0402LF"
WATTAGE"1/16W"
ROOM"ADC_TI_BOM1"
MATERIAL"CHIP"
TOLERANCE"5%"
VALUE"0"
CDS_LIB"pure_quanta"
PART_NUMBER"CS00002JB13";
"B"
$PN"2"98;
"A"
$PN"1"97;
%"ADC128D818CIMTXNOPB"
"1","(-1575,1950)","0","pure_quanta","I142";
;
LOCATION"U51"
$SEC"1"
CDS_SEC"1"
VALUE"ADC128D818CIMTX/NOPB"
PART_TYPE"SMLF"
MATERIAL"IC"
ROOM"ADC_TI_BOM1"
CDS_LIB"pure_quanta"
CDS_LMAN_SYM_OUTLINE"-250,475,250,-475"
PIN_NAMES_ROTATE"True"
PART_NUMBER"AL000128K00";
"INT# \B"
$PN"6"102;
"GND"
$PN"4"4;
"SCL"
$PN"3"104;
"SDA"
$PN"2"99;
"IN0"
$PN"16"93;
"IN1"
$PN"15"92;
"IN2"
$PN"14"91;
"IN3"
$PN"13"90;
"IN4"
$PN"12"89;
"IN5"
$PN"11"88;
"IN6"
$PN"10"87;
"IN7"
$PN"9"86;
"A1"
$PN"8"101;
"A0"
$PN"7"85;
"V+"
$PN"5"83;
"VREF"
$PN"1"84;
%"UNIVERSAL_GND"
"1","(-1000,1325)","0","pure_quanta_power","I143";
;
CDS_LIB"pure_quanta_power"
HDL_POWER"GND";
"A"4;
%"Q_RES"
"1","(-8400,5625)","0","pure_quanta","I15";
;
LOCATION"R1263"
$SEC"1"
CDS_SEC"1"
ROOM"ADC_TI_BOM1"
TOLERANCE"5%"
MATERIAL"CHIP"
VALUE"0"
CDS_LIB"pure_quanta"
WATTAGE"1/16W"
PACK_TYPE"0402LF"
PART_NUMBER"CS00002JB13";
"B"
$PN"2"77;
"A"
$PN"1"78;
%"Q_CAP"
"1","(-3775,5200)","0","pure_quanta","I152";
;
LOCATION"C1076"
$SEC"1"
CDS_SEC"1"
VALUE"10UF"
VOLTAGE"16V"
PACK_TYPE"C0805"
TOLERANCE"10%"
MATERIAL"X6S"
CDS_LIB"pure_quanta"
PART_NUMBER"CH6103KEA00";
"B"
$PN"2"5;
"A"
$PN"1"79;
%"UNIVERSAL_GND"
"1","(-3775,5000)","0","pure_quanta_power","I153";
;
CDS_LIB"pure_quanta_power"
HDL_POWER"GND";
"A"5;
%"Q_RES"
"1","(-3425,5375)","0","pure_quanta","I154";
;
LOCATION"R1230"
$SEC"1"
CDS_SEC"1"
VALUE"2K"
TOLERANCE"1%"
MATERIAL"CHIP"
PACK_TYPE"0402LF"
WATTAGE"1/16W"
CDS_LIB"pure_quanta"
PART_NUMBER"CS22002FB07";
"B"
$PN"2"43;
"A"
$PN"1"79;
%"UNIVERSAL_GND"
"1","(-2875,4100)","0","pure_quanta_power","I155";
;
CDS_LIB"pure_quanta_power"
HDL_POWER"GND";
"A"44;
%"MAX11617EEET"
"1","(-2375,4750)","0","pure_quanta","I156";
;
LOCATION"U50"
SEC"1"
ROOM"ADC_MAM_BOM2"
PART_TYPE"SMLF"
MATERIAL"EMPTY"
VALUE"MAX11617EEE+T"
CDS_LIB"pure_quanta"
NEEDS_NO_SIZE"TRUE"
CDS_LMAN_SYM_OUTLINE"-250,400,250,-400"
SEC_TYPE""
PART_NUMBER"AL011617W00";
"VDD"
$PN"16"46;
"GND"
$PN"15"45;
"SDA"
$PN"14"49;
"SCL"
$PN"13"59;
"AIN7"
$PN"12"107;
"AIN6"
$PN"11"108;
"AIN5"
$PN"10"103;
"AIN4"
$PN"9"57;
"AIN3"
$PN"8"80;
"AIN2"
$PN"7"48;
"AIN1"
$PN"6"106;
"AIN0"
$PN"5"105;
"AIN8"
$PN"4"44;
"AIN9"
$PN"3"44;
"AIN10"
$PN"2"44;
"AIN11||REF"
$PN"1"43;
%"UNIVERSAL_GND"
"1","(-1850,4150)","0","pure_quanta_power","I157";
;
CDS_LIB"pure_quanta_power"
HDL_POWER"GND";
"A"45;
%"Q_RES"
"1","(-8400,5775)","0","pure_quanta","I16";
;
LOCATION"R1260"
$SEC"1"
CDS_SEC"1"
ROOM"ADC_MAM_BOM2"
MATERIAL"EMPTY"
VALUE"0"
TOLERANCE"5%"
PACK_TYPE"0402LF"
WATTAGE"1/16W"
CDS_LIB"pure_quanta"
PART_NUMBER"CS00002JB13";
"B"
$PN"2"76;
"A"
$PN"1"78;
%"UNIVERSAL_GND"
"1","(-1450,5000)","0","pure_quanta_power","I164";
;
CDS_LIB"pure_quanta_power"
HDL_POWER"GND";
"A"6;
%"Q_CAP"
"1","(-1450,5175)","2","pure_quanta","I165";
;
LOCATION"C1075"
$SEC"1"
CDS_SEC"1"
PACK_TYPE"0402"
VALUE"0.1UF"
VOLTAGE"25V"
MATERIAL"X7R"
TOLERANCE"10%"
CDS_LIB"pure_quanta"
PART_NUMBER"CH4104K1B00";
"B"
$PN"2"6;
"A"
$PN"1"46;
%"Q_CAP"
"1","(-1075,5175)","0","pure_quanta","I166";
;
LOCATION"C1077"
$SEC"1"
CDS_SEC"1"
MATERIAL"X6S"
PACK_TYPE"C0805"
VALUE"10UF"
VOLTAGE"16V"
TOLERANCE"10%"
CDS_LIB"pure_quanta"
PART_NUMBER"CH6103KEA00";
"B"
$PN"2"7;
"A"
$PN"1"46;
%"UNIVERSAL_GND"
"1","(-1075,5000)","0","pure_quanta_power","I167";
;
CDS_LIB"pure_quanta_power"
HDL_POWER"GND";
"A"7;
%"Q_INDUCTOR"
"1","(-750,5400)","0","pure_quanta","I168";
;
LOCATION"L24"
$SEC"1"
CDS_SEC"1"
MATERIAL"IND"
VALUE"BLM18PG300SN1D "
PACK_TYPE"SMLF"
NEEDS_NO_SIZE"TRUE"
CDS_LIB"pure_quanta"
PART_NUMBER"TMP_QCX8PG300001";
"1"
$PN"1"46;
"2"
$PN"2"8;
%"UNIVERSAL_POWER"
"1","(-325,5600)","0","pure_quanta_power","I169";
;
HDL_POWER"P3V3_AUX"
CDS_LIB"pure_quanta_power";
"A"8;
%"UNIVERSAL_POWER"
"1","(-8950,3475)","0","pure_quanta_power","I170";
;
HDL_POWER"P1V2_AUX"
CDS_LIB"pure_quanta_power";
"A"9;
%"Q_CAP"
"1","(-7525,2575)","0","pure_quanta","I173";
;
LOCATION"C1078"
$SEC"1"
CDS_SEC"1"
VOLTAGE"50V"
TOLERANCE"5%"
PACK_TYPE"0402"
VALUE"100PF"
MATERIAL"EMPTY"
ROOM"ADC_MAM_BOM2"
CDS_LIB"pure_quanta"
PART_NUMBER"CH11006JB18";
"B"
$PN"2"10;
"A"
$PN"1"50;
%"UNIVERSAL_GND"
"1","(-7525,2300)","0","pure_quanta_power","I174";
;
CDS_LIB"pure_quanta_power"
HDL_POWER"GND";
"A"10;
%"Q_CAP"
"1","(-7875,2575)","2","pure_quanta","I175";
;
LOCATION"C1086"
$SEC"1"
CDS_SEC"1"
ROOM"ADC_TI_BOM1"
PACK_TYPE"0402"
MATERIAL"X7R"
TOLERANCE"10%"
VOLTAGE"25V"
VALUE"0.1UF"
CDS_LIB"pure_quanta"
PART_NUMBER"CH4104K1B00";
"B"
$PN"2"11;
"A"
$PN"1"51;
%"UNIVERSAL_GND"
"1","(-7875,2300)","0","pure_quanta_power","I176";
;
CDS_LIB"pure_quanta_power"
HDL_POWER"GND";
"A"11;
%"Q_RES"
"1","(-8250,2975)","0","pure_quanta","I177";
;
LOCATION"R1245"
$SEC"1"
CDS_SEC"1"
VALUE"0"
MATERIAL"EMPTY"
TOLERANCE"5%"
ROOM"ADC_MAM_BOM2"
PACK_TYPE"0402LF"
WATTAGE"1/16W"
CDS_LIB"pure_quanta"
PART_NUMBER"CS00002JB13";
"B"
$PN"2"50;
"A"
$PN"1"74;
%"Q_RES"
"1","(-8250,2825)","0","pure_quanta","I178";
;
LOCATION"R1251"
$SEC"1"
CDS_SEC"1"
ROOM"ADC_TI_BOM1"
VALUE"0"
MATERIAL"CHIP"
TOLERANCE"5%"
PACK_TYPE"0402LF"
WATTAGE"1/16W"
CDS_LIB"pure_quanta"
PART_NUMBER"CS00002JB13";
"B"
$PN"2"51;
"A"
$PN"1"74;
%"Q_RES"
"2","(-8950,3225)","0","pure_quanta","I179";
;
LOCATION"R1232"
$SEC"1"
CDS_SEC"1"
MATERIAL"CHIP"
WATTAGE"1/16W"
TOLERANCE"1%"
VALUE"5.11K"
PACK_TYPE"0402LF"
CDS_LIB"pure_quanta"
PART_NUMBER"CS25112FB04";
"A"
$PN"1"9;
"B"
$PN"2"74;
%"UNIVERSAL_GND"
"1","(-8975,3975)","0","pure_quanta_power","I18";
;
CDS_LIB"pure_quanta_power"
HDL_POWER"GND";
"A"12;
%"UNIVERSAL_GND"
"1","(-8950,2350)","0","pure_quanta_power","I181";
;
CDS_LIB"pure_quanta_power"
HDL_POWER"GND";
"A"13;
%"UNIVERSAL_POWER"
"1","(-9025,1875)","0","pure_quanta_power","I183";
;
HDL_POWER"P1V8_CPU0_RT_1D"
CDS_LIB"pure_quanta_power";
"A"14;
%"Q_CAP"
"1","(-7300,975)","0","pure_quanta","I185";
;
LOCATION"C1079"
$SEC"1"
CDS_SEC"1"
VOLTAGE"50V"
VALUE"100PF"
PACK_TYPE"0402"
MATERIAL"EMPTY"
TOLERANCE"5%"
ROOM"ADC_MAM_BOM2"
CDS_LIB"pure_quanta"
PART_NUMBER"CH11006JB18";
"B"
$PN"2"15;
"A"
$PN"1"52;
%"UNIVERSAL_GND"
"1","(-7300,700)","0","pure_quanta_power","I186";
;
CDS_LIB"pure_quanta_power"
HDL_POWER"GND";
"A"15;
%"Q_CAP"
"1","(-7825,975)","2","pure_quanta","I187";
;
LOCATION"C1087"
$SEC"1"
CDS_SEC"1"
TOLERANCE"10%"
MATERIAL"X7R"
VOLTAGE"25V"
PACK_TYPE"0402"
VALUE"0.1UF"
ROOM"ADC_TI_BOM1"
CDS_LIB"pure_quanta"
PART_NUMBER"CH4104K1B00";
"B"
$PN"2"16;
"A"
$PN"1"53;
%"UNIVERSAL_GND"
"1","(-7825,700)","0","pure_quanta_power","I188";
;
CDS_LIB"pure_quanta_power"
HDL_POWER"GND";
"A"16;
%"Q_RES"
"1","(-8200,1375)","0","pure_quanta","I189";
;
LOCATION"R1246"
$SEC"1"
CDS_SEC"1"
VALUE"0"
MATERIAL"EMPTY"
TOLERANCE"5%"
ROOM"ADC_MAM_BOM2"
PACK_TYPE"0402LF"
WATTAGE"1/16W"
CDS_LIB"pure_quanta"
PART_NUMBER"CS00002JB13";
"B"
$PN"2"52;
"A"
$PN"1"73;
%"Q_RES"
"2","(-8975,4700)","0","pure_quanta","I19";
;
LOCATION"R1237"
$SEC"1"
CDS_SEC"1"
TOLERANCE"1%"
VALUE"5.11K"
PACK_TYPE"0402LF"
MATERIAL"CHIP"
WATTAGE"1/16W"
CDS_LIB"pure_quanta"
PART_NUMBER"CS25112FB04";
"A"
$PN"1"20;
"B"
$PN"2"82;
%"Q_RES"
"1","(-8200,1225)","0","pure_quanta","I190";
;
LOCATION"R1252"
$SEC"1"
CDS_SEC"1"
ROOM"ADC_TI_BOM1"
MATERIAL"CHIP"
VALUE"0"
TOLERANCE"5%"
PACK_TYPE"0402LF"
WATTAGE"1/16W"
CDS_LIB"pure_quanta"
PART_NUMBER"CS00002JB13";
"B"
$PN"2"53;
"A"
$PN"1"73;
%"Q_RES"
"2","(-9025,1625)","0","pure_quanta","I191";
;
LOCATION"R1231"
$SEC"1"
CDS_SEC"1"
TOLERANCE"1%"
WATTAGE"1/16W"
MATERIAL"CHIP"
VALUE"5.11K"
PACK_TYPE"0402LF"
CDS_LIB"pure_quanta"
PART_NUMBER"CS25112FB04";
"A"
$PN"1"14;
"B"
$PN"2"73;
%"UNIVERSAL_GND"
"1","(-9025,750)","0","pure_quanta_power","I193";
;
CDS_LIB"pure_quanta_power"
HDL_POWER"GND";
"A"17;
%"Q_RES"
"2","(-6800,6000)","0","pure_quanta","I194";
;
LOCATION"R1234"
$SEC"1"
CDS_SEC"1"
VALUE"5.11K"
WATTAGE"1/16W"
PACK_TYPE"0402LF"
TOLERANCE"1%"
MATERIAL"CHIP"
CDS_LIB"pure_quanta"
PART_NUMBER"CS25112FB04";
"A"
$PN"1"18;
"B"
$PN"2"70;
%"UNIVERSAL_POWER"
"1","(-6800,6250)","0","pure_quanta_power","I195";
;
HDL_POWER"P1V8_CPU1_RT_1D"
CDS_LIB"pure_quanta_power";
"A"18;
%"Q_CAP"
"1","(-4950,5375)","0","pure_quanta","I198";
;
LOCATION"C1083"
$SEC"1"
CDS_SEC"1"
TOLERANCE"5%"
VALUE"100PF"
VOLTAGE"50V"
PACK_TYPE"0402"
MATERIAL"EMPTY"
ROOM"ADC_MAM_BOM2"
CDS_LIB"pure_quanta"
PART_NUMBER"CH11006JB18";
"B"
$PN"2"19;
"A"
$PN"1"47;
%"UNIVERSAL_GND"
"1","(-4950,5100)","0","pure_quanta_power","I199";
;
CDS_LIB"pure_quanta_power"
HDL_POWER"GND";
"A"19;
%"UNIVERSAL_POWER"
"1","(-8975,4950)","0","pure_quanta_power","I20";
;
HDL_POWER"P1V8_AUX"
CDS_LIB"pure_quanta_power";
"A"20;
%"Q_CAP"
"1","(-5550,5350)","2","pure_quanta","I200";
;
LOCATION"C1091"
$SEC"1"
CDS_SEC"1"
VOLTAGE"25V"
VALUE"0.1UF"
ROOM"ADC_TI_BOM1"
TOLERANCE"10%"
PACK_TYPE"0402"
MATERIAL"X7R"
CDS_LIB"pure_quanta"
PART_NUMBER"CH4104K1B00";
"B"
$PN"2"21;
"A"
$PN"1"69;
%"UNIVERSAL_GND"
"1","(-5550,5075)","0","pure_quanta_power","I201";
;
CDS_LIB"pure_quanta_power"
HDL_POWER"GND";
"A"21;
%"Q_RES"
"1","(-5925,5750)","0","pure_quanta","I202";
;
LOCATION"R1250"
$SEC"1"
CDS_SEC"1"
MATERIAL"EMPTY"
TOLERANCE"5%"
VALUE"0"
ROOM"ADC_MAM_BOM2"
PACK_TYPE"0402LF"
WATTAGE"1/16W"
CDS_LIB"pure_quanta"
PART_NUMBER"CS00002JB13";
"B"
$PN"2"47;
"A"
$PN"1"70;
%"Q_RES"
"1","(-5925,5600)","0","pure_quanta","I203";
;
LOCATION"R1257"
$SEC"1"
CDS_SEC"1"
TOLERANCE"5%"
VALUE"0"
MATERIAL"CHIP"
ROOM"ADC_TI_BOM1"
CDS_LIB"pure_quanta"
WATTAGE"1/16W"
PACK_TYPE"0402LF"
PART_NUMBER"CS00002JB13";
"B"
$PN"2"69;
"A"
$PN"1"70;
%"UNIVERSAL_GND"
"1","(-6800,5150)","0","pure_quanta_power","I205";
;
CDS_LIB"pure_quanta_power"
HDL_POWER"GND";
"A"22;
%"UNIVERSAL_POWER"
"1","(-6750,4725)","0","pure_quanta_power","I207";
;
HDL_POWER"PVDD_33_S5"
CDS_LIB"pure_quanta_power";
"A"23;
%"Q_CAP"
"1","(-5200,3825)","0","pure_quanta","I209";
;
LOCATION"C1082"
$SEC"1"
CDS_SEC"1"
MATERIAL"EMPTY"
PACK_TYPE"0402"
TOLERANCE"5%"
VOLTAGE"50V"
VALUE"100PF"
ROOM"ADC_MAM_BOM2"
CDS_LIB"pure_quanta"
PART_NUMBER"CH11006JB18";
"B"
$PN"2"24;
"A"
$PN"1"68;
%"Q_RES"
"1","(-8350,4300)","0","pure_quanta","I21";
;
LOCATION"R1259"
$SEC"1"
CDS_SEC"1"
ROOM"ADC_TI_BOM1"
TOLERANCE"5%"
MATERIAL"CHIP"
VALUE"0"
CDS_LIB"pure_quanta"
WATTAGE"1/16W"
PACK_TYPE"0402LF"
PART_NUMBER"CS00002JB13";
"B"
$PN"2"71;
"A"
$PN"1"82;
%"UNIVERSAL_GND"
"1","(-5200,3550)","0","pure_quanta_power","I210";
;
CDS_LIB"pure_quanta_power"
HDL_POWER"GND";
"A"24;
%"Q_CAP"
"1","(-5675,3825)","2","pure_quanta","I211";
;
LOCATION"C1089"
$SEC"1"
CDS_SEC"1"
MATERIAL"X7R"
TOLERANCE"10%"
VALUE"0.1UF"
ROOM"ADC_TI_BOM1"
PACK_TYPE"0402"
VOLTAGE"25V"
CDS_LIB"pure_quanta"
PART_NUMBER"CH4104K1B00";
"B"
$PN"2"25;
"A"
$PN"1"81;
%"UNIVERSAL_GND"
"1","(-5675,3550)","0","pure_quanta_power","I212";
;
CDS_LIB"pure_quanta_power"
HDL_POWER"GND";
"A"25;
%"Q_RES"
"1","(-6050,4225)","0","pure_quanta","I213";
;
LOCATION"R1248"
$SEC"1"
CDS_SEC"1"
VALUE"0"
MATERIAL"EMPTY"
TOLERANCE"5%"
ROOM"ADC_MAM_BOM2"
PACK_TYPE"0402LF"
WATTAGE"1/16W"
CDS_LIB"pure_quanta"
PART_NUMBER"CS00002JB13";
"B"
$PN"2"68;
"A"
$PN"1"72;
%"Q_RES"
"1","(-6050,4075)","0","pure_quanta","I214";
;
LOCATION"R1255"
$SEC"1"
CDS_SEC"1"
ROOM"ADC_TI_BOM1"
TOLERANCE"5%"
MATERIAL"CHIP"
VALUE"0"
PACK_TYPE"0402LF"
WATTAGE"1/16W"
CDS_LIB"pure_quanta"
PART_NUMBER"CS00002JB13";
"B"
$PN"2"81;
"A"
$PN"1"72;
%"Q_RES"
"2","(-6750,4475)","0","pure_quanta","I215";
;
LOCATION"R1235"
$SEC"1"
CDS_SEC"1"
TOLERANCE"1%"
VALUE"5.11K"
MATERIAL"CHIP"
PACK_TYPE"0402LF"
WATTAGE"1/16W"
CDS_LIB"pure_quanta"
PART_NUMBER"CS25112FB04";
"A"
$PN"1"23;
"B"
$PN"2"72;
%"Q_RES"
"2","(-6750,3950)","0","pure_quanta","I216";
;
LOCATION"R1224"
$SEC"1"
CDS_SEC"1"
VALUE"4.7K"
TOLERANCE"1%"
MATERIAL"CHIP"
WATTAGE"1/16W"
PACK_TYPE"0402LF"
CDS_LIB"pure_quanta"
PART_NUMBER"CS24702FB06";
"A"
$PN"1"72;
"B"
$PN"2"26;
%"UNIVERSAL_GND"
"1","(-6750,3600)","0","pure_quanta_power","I217";
;
CDS_LIB"pure_quanta_power"
HDL_POWER"GND";
"A"26;
%"UNIVERSAL_POWER"
"1","(-6850,3300)","0","pure_quanta_power","I218";
;
HDL_POWER"PVDD18_S5_P0"
CDS_LIB"pure_quanta_power";
"A"27;
%"Q_RES"
"1","(-8350,4450)","0","pure_quanta","I22";
;
LOCATION"R1258"
$SEC"1"
CDS_SEC"1"
TOLERANCE"5%"
VALUE"0"
MATERIAL"EMPTY"
ROOM"ADC_MAM_BOM2"
CDS_LIB"pure_quanta"
WATTAGE"1/16W"
PACK_TYPE"0402LF"
PART_NUMBER"CS00002JB13";
"B"
$PN"2"75;
"A"
$PN"1"82;
%"Q_CAP"
"1","(-5425,2400)","0","pure_quanta","I221";
;
LOCATION"C1080"
$SEC"1"
CDS_SEC"1"
TOLERANCE"5%"
VOLTAGE"50V"
VALUE"100PF"
PACK_TYPE"0402"
MATERIAL"EMPTY"
ROOM"ADC_MAM_BOM2"
CDS_LIB"pure_quanta"
PART_NUMBER"CH11006JB18";
"B"
$PN"2"28;
"A"
$PN"1"66;
%"UNIVERSAL_GND"
"1","(-5425,2125)","0","pure_quanta_power","I222";
;
CDS_LIB"pure_quanta_power"
HDL_POWER"GND";
"A"28;
%"Q_CAP"
"1","(-5775,2400)","2","pure_quanta","I223";
;
LOCATION"C1088"
$SEC"1"
CDS_SEC"1"
ROOM"ADC_TI_BOM1"
PACK_TYPE"0402"
TOLERANCE"10%"
MATERIAL"X7R"
VOLTAGE"25V"
VALUE"0.1UF"
CDS_LIB"pure_quanta"
PART_NUMBER"CH4104K1B00";
"B"
$PN"2"29;
"A"
$PN"1"65;
%"UNIVERSAL_GND"
"1","(-5775,2125)","0","pure_quanta_power","I224";
;
CDS_LIB"pure_quanta_power"
HDL_POWER"GND";
"A"29;
%"Q_RES"
"1","(-6150,2800)","0","pure_quanta","I225";
;
LOCATION"R1247"
$SEC"1"
CDS_SEC"1"
VALUE"0"
TOLERANCE"5%"
MATERIAL"EMPTY"
ROOM"ADC_MAM_BOM2"
PACK_TYPE"0402LF"
WATTAGE"1/16W"
CDS_LIB"pure_quanta"
PART_NUMBER"CS00002JB13";
"B"
$PN"2"66;
"A"
$PN"1"67;
%"Q_RES"
"1","(-6150,2650)","0","pure_quanta","I226";
;
LOCATION"R1254"
$SEC"1"
CDS_SEC"1"
ROOM"ADC_TI_BOM1"
TOLERANCE"5%"
VALUE"0"
MATERIAL"CHIP"
PACK_TYPE"0402LF"
WATTAGE"1/16W"
CDS_LIB"pure_quanta"
PART_NUMBER"CS00002JB13";
"B"
$PN"2"65;
"A"
$PN"1"67;
%"Q_RES"
"2","(-6850,3050)","0","pure_quanta","I227";
;
LOCATION"R1233"
$SEC"1"
CDS_SEC"1"
VALUE"5.11K"
TOLERANCE"1%"
PACK_TYPE"0402LF"
MATERIAL"CHIP"
WATTAGE"1/16W"
CDS_LIB"pure_quanta"
PART_NUMBER"CS25112FB04";
"A"
$PN"1"27;
"B"
$PN"2"67;
%"UNIVERSAL_GND"
"1","(-6850,2175)","0","pure_quanta_power","I229";
;
CDS_LIB"pure_quanta_power"
HDL_POWER"GND";
"A"30;
%"Q_RES"
"2","(-6675,1525)","0","pure_quanta","I230";
;
LOCATION"R1236"
$SEC"1"
CDS_SEC"1"
PACK_TYPE"0402LF"
WATTAGE"1/16W"
TOLERANCE"1%"
MATERIAL"CHIP"
VALUE"5.11K"
CDS_LIB"pure_quanta"
PART_NUMBER"CS25112FB04";
"A"
$PN"1"31;
"B"
$PN"2"64;
%"Q_RES"
"1","(-5975,1275)","0","pure_quanta","I231";
;
LOCATION"R1249"
$SEC"1"
CDS_SEC"1"
ROOM"ADC_MAM_BOM2"
TOLERANCE"5%"
VALUE"0"
MATERIAL"EMPTY"
CDS_LIB"pure_quanta"
WATTAGE"1/16W"
PACK_TYPE"0402LF"
PART_NUMBER"CS00002JB13";
"B"
$PN"2"60;
"A"
$PN"1"64;
%"Q_CAP"
"1","(-5250,875)","0","pure_quanta","I232";
;
LOCATION"C1081"
$SEC"1"
CDS_SEC"1"
ROOM"ADC_MAM_BOM2"
VALUE"100PF"
PACK_TYPE"0402"
TOLERANCE"5%"
VOLTAGE"50V"
MATERIAL"EMPTY"
CDS_LIB"pure_quanta"
PART_NUMBER"CH11006JB18";
"B"
$PN"2"32;
"A"
$PN"1"60;
%"UNIVERSAL_POWER"
"1","(-6675,1775)","0","pure_quanta_power","I233";
;
HDL_POWER"PVDD18_S5_P1"
CDS_LIB"pure_quanta_power";
"A"31;
%"UNIVERSAL_GND"
"1","(-5250,600)","0","pure_quanta_power","I236";
;
CDS_LIB"pure_quanta_power"
HDL_POWER"GND";
"A"32;
%"Q_CAP"
"1","(-5600,875)","2","pure_quanta","I237";
;
LOCATION"C1090"
$SEC"1"
CDS_SEC"1"
VOLTAGE"25V"
TOLERANCE"10%"
MATERIAL"X7R"
VALUE"0.1UF"
PACK_TYPE"0402"
ROOM"ADC_TI_BOM1"
CDS_LIB"pure_quanta"
PART_NUMBER"CH4104K1B00";
"B"
$PN"2"33;
"A"
$PN"1"63;
%"UNIVERSAL_GND"
"1","(-5600,600)","0","pure_quanta_power","I238";
;
CDS_LIB"pure_quanta_power"
HDL_POWER"GND";
"A"33;
%"Q_RES"
"1","(-5975,1125)","0","pure_quanta","I239";
;
LOCATION"R1256"
$SEC"1"
CDS_SEC"1"
MATERIAL"CHIP"
TOLERANCE"5%"
VALUE"0"
ROOM"ADC_TI_BOM1"
CDS_LIB"pure_quanta"
WATTAGE"1/16W"
PACK_TYPE"0402LF"
PART_NUMBER"CS00002JB13";
"B"
$PN"2"63;
"A"
$PN"1"64;
%"UNIVERSAL_GND"
"1","(-6675,650)","0","pure_quanta_power","I241";
;
CDS_LIB"pure_quanta_power"
HDL_POWER"GND";
"A"34;
%"Q_RES"
"2","(-8975,4225)","0","pure_quanta","I242";
;
LOCATION"R1229"
$SEC"1"
CDS_SEC"1"
TOLERANCE"1%"
VALUE"18K"
MATERIAL"CHIP"
WATTAGE"1/16W"
PACK_TYPE"0402LF"
CDS_LIB"pure_quanta"
PART_NUMBER"CS31802FB04";
"A"
$PN"1"82;
"B"
$PN"2"12;
%"Q_RES"
"2","(-8950,2700)","0","pure_quanta","I243";
;
LOCATION"R1221"
$SEC"1"
CDS_SEC"1"
TOLERANCE"1%"
MATERIAL"CHIP"
VALUE"18K"
WATTAGE"1/16W"
PACK_TYPE"0402LF"
CDS_LIB"pure_quanta"
PART_NUMBER"CS31802FB04";
"A"
$PN"1"74;
"B"
$PN"2"13;
%"Q_RES"
"2","(-9025,1100)","0","pure_quanta","I244";
;
LOCATION"R1220"
$SEC"1"
CDS_SEC"1"
PACK_TYPE"0402LF"
MATERIAL"CHIP"
VALUE"18K"
WATTAGE"1/16W"
TOLERANCE"1%"
CDS_LIB"pure_quanta"
PART_NUMBER"CS31802FB04";
"A"
$PN"1"73;
"B"
$PN"2"17;
%"Q_RES"
"2","(-6800,5500)","0","pure_quanta","I245";
;
LOCATION"R1223"
$SEC"1"
CDS_SEC"1"
TOLERANCE"1%"
PACK_TYPE"0402LF"
VALUE"18K"
MATERIAL"CHIP"
WATTAGE"1/16W"
CDS_LIB"pure_quanta"
PART_NUMBER"CS31802FB04";
"A"
$PN"1"70;
"B"
$PN"2"22;
%"Q_RES"
"2","(-6850,2525)","0","pure_quanta","I246";
;
LOCATION"R1222"
$SEC"1"
CDS_SEC"1"
PACK_TYPE"0402LF"
VALUE"18K"
MATERIAL"CHIP"
WATTAGE"1/16W"
TOLERANCE"1%"
CDS_LIB"pure_quanta"
PART_NUMBER"CS31802FB04";
"A"
$PN"1"67;
"B"
$PN"2"30;
%"Q_RES"
"2","(-6675,1000)","0","pure_quanta","I247";
;
LOCATION"R1225"
$SEC"1"
CDS_SEC"1"
MATERIAL"CHIP"
VALUE"18K"
TOLERANCE"1%"
PACK_TYPE"0402LF"
WATTAGE"1/16W"
CDS_LIB"pure_quanta"
PART_NUMBER"CS31802FB04";
"A"
$PN"1"64;
"B"
$PN"2"34;
%"UNIVERSAL_GND"
"1","(-8050,5075)","0","pure_quanta_power","I42";
;
CDS_LIB"pure_quanta_power"
HDL_POWER"GND";
"A"35;
%"Q_CAP"
"1","(-8050,5350)","2","pure_quanta","I43";
;
LOCATION"C1093"
$SEC"1"
CDS_SEC"1"
ROOM"ADC_TI_BOM1"
VALUE"0.1UF"
VOLTAGE"25V"
TOLERANCE"10%"
MATERIAL"X7R"
PACK_TYPE"0402"
CDS_LIB"pure_quanta"
PART_NUMBER"CH4104K1B00";
"B"
$PN"2"35;
"A"
$PN"1"77;
%"UNIVERSAL_GND"
"1","(-7700,5075)","0","pure_quanta_power","I44";
;
CDS_LIB"pure_quanta_power"
HDL_POWER"GND";
"A"36;
%"Q_CAP"
"1","(-7700,5350)","0","pure_quanta","I45";
;
LOCATION"C1085"
$SEC"1"
CDS_SEC"1"
TOLERANCE"5%"
MATERIAL"EMPTY"
VOLTAGE"50V"
VALUE"100PF"
PACK_TYPE"0402"
ROOM"ADC_MAM_BOM2"
CDS_LIB"pure_quanta"
PART_NUMBER"CH11006JB18";
"B"
$PN"2"36;
"A"
$PN"1"76;
%"UNIVERSAL_GND"
"1","(-7975,3750)","0","pure_quanta_power","I46";
;
CDS_LIB"pure_quanta_power"
HDL_POWER"GND";
"A"37;
%"UNIVERSAL_GND"
"1","(-7625,3750)","0","pure_quanta_power","I49";
;
CDS_LIB"pure_quanta_power"
HDL_POWER"GND";
"A"38;
%"UNIVERSAL_GND"
"1","(-4250,350)","0","pure_quanta_power","I55";
;
CDS_LIB"pure_quanta_power"
HDL_POWER"GND";
"A"39;
%"UNIVERSAL_GND"
"1","(-4500,350)","0","pure_quanta_power","I56";
;
CDS_LIB"pure_quanta_power"
HDL_POWER"GND";
"A"40;
%"Q_RES"
"2","(-4500,575)","0","pure_quanta","I57";
;
LOCATION"R1240"
$SEC"1"
CDS_SEC"1"
ROOM"ADC_TI_BOM1"
MATERIAL"CHIP"
TOLERANCE"1%"
VALUE"1K"
PACK_TYPE"0402LF"
WATTAGE"1/16W"
CDS_LIB"pure_quanta"
PART_NUMBER"CS21002FB06";
"A"
$PN"1"94;
"B"
$PN"2"40;
%"Q_RES"
"2","(-4250,575)","0","pure_quanta","I58";
;
LOCATION"R1242"
$SEC"1"
CDS_SEC"1"
PACK_TYPE"0402LF"
TOLERANCE"1%"
VALUE"1K"
WATTAGE"1/16W"
MATERIAL"CHIP"
ROOM"ADC_TI_BOM1"
CDS_LIB"pure_quanta"
PART_NUMBER"CS21002FB06";
"A"
$PN"1"95;
"B"
$PN"2"39;
%"Q_RES"
"2","(-4500,1175)","0","pure_quanta","I59";
;
LOCATION"R1239"
$SEC"1"
CDS_SEC"1"
ROOM"ADC_TI_BOM1"
MATERIAL"EMPTY"
PACK_TYPE"0402LF"
VALUE"1K"
TOLERANCE"1%"
WATTAGE"1/16W"
CDS_LIB"pure_quanta"
PART_NUMBER"CS21002FB06";
"A"
$PN"1"62;
"B"
$PN"2"94;
%"Q_RES"
"2","(-4250,1175)","0","pure_quanta","I60";
;
LOCATION"R1241"
$SEC"1"
CDS_SEC"1"
MATERIAL"EMPTY"
PACK_TYPE"0402LF"
TOLERANCE"1%"
WATTAGE"1/16W"
VALUE"1K"
ROOM"ADC_TI_BOM1"
CDS_LIB"pure_quanta"
PART_NUMBER"CS21002FB06";
"A"
$PN"1"62;
"B"
$PN"2"95;
%"UNIVERSAL_POWER"
"1","(-4500,1575)","0","pure_quanta_power","I61";
;
HDL_POWER"P3V3_AUX"
CDS_LIB"pure_quanta_power";
"A"62;
%"UNIVERSAL_POWER"
"1","(-4600,2800)","0","pure_quanta_power","I66";
;
HDL_POWER"P3V3_AUX"
CDS_LIB"pure_quanta_power";
"A"41;
%"UNIVERSAL_GND"
"1","(-4125,2025)","0","pure_quanta_power","I67";
;
CDS_LIB"pure_quanta_power"
HDL_POWER"GND";
"A"61;
%"Q_CAP"
"1","(-4125,2350)","2","pure_quanta","I68";
;
LOCATION"C1094"
$SEC"1"
CDS_SEC"1"
PACK_TYPE"0402"
TOLERANCE"10%"
VALUE"0.1UF"
MATERIAL"X7R"
ROOM"ADC_TI_BOM1"
VOLTAGE"25V"
CDS_LIB"pure_quanta"
PART_NUMBER"CH4104K1B00";
"B"
$PN"2"61;
"A"
$PN"1"83;
%"Q_INDUCTOR"
"1","(-4300,2575)","0","pure_quanta","I69";
;
LOCATION"L25"
$SEC"1"
CDS_SEC"1"
PACK_TYPE"SMLF"
MATERIAL"IND"
VALUE"BLM18PG300SN1D "
ROOM"ADC_TI_BOM1"
CDS_LIB"pure_quanta"
NEEDS_NO_SIZE"TRUE"
PART_NUMBER"TMP_QCX8PG300001";
"1"
$PN"1"41;
"2"
$PN"2"83;
%"Q_CAP"
"1","(-7975,4025)","2","pure_quanta","I76";
;
LOCATION"C1092"
$SEC"1"
CDS_SEC"1"
VOLTAGE"25V"
VALUE"0.1UF"
MATERIAL"X7R"
TOLERANCE"10%"
PACK_TYPE"0402"
ROOM"ADC_TI_BOM1"
CDS_LIB"pure_quanta"
PART_NUMBER"CH4104K1B00";
"B"
$PN"2"37;
"A"
$PN"1"71;
%"Q_CAP"
"1","(-7625,4025)","0","pure_quanta","I77";
;
LOCATION"C1084"
$SEC"1"
CDS_SEC"1"
TOLERANCE"5%"
VOLTAGE"50V"
VALUE"100PF"
PACK_TYPE"0402"
MATERIAL"EMPTY"
ROOM"ADC_MAM_BOM2"
CDS_LIB"pure_quanta"
PART_NUMBER"CH11006JB18";
"B"
$PN"2"38;
"A"
$PN"1"75;
%"UNIVERSAL_GND"
"1","(-9025,5175)","0","pure_quanta_power","I9";
;
CDS_LIB"pure_quanta_power"
HDL_POWER"GND";
"A"42;
END.
